(kicad_pcb
	(version 20260206)
	(generator "pcbnew")
	(generator_version "10.0")
	(general
		(thickness 1.6)
		(legacy_teardrops no)
	)
	(paper "A4")
	(title_block
		(title "04192023_DAF0TMB3IC0_F0TG_MB_C_brd_V02_OCP.brd")
		(comment 1 "Grand Teton / footprint 3955 of 8354 (U25), pads 1086-1199 of 6102")
	)
	(layers
		(0 "F.Cu" signal "TOP")
		(4 "In1.Cu" signal "GND")
		(6 "In2.Cu" signal "IN1")
		(8 "In3.Cu" signal "GND1")
		(10 "In4.Cu" signal "IN2")
		(12 "In5.Cu" signal "GND2")
		(14 "In6.Cu" signal "IN3")
		(16 "In7.Cu" signal "GND3")
		(18 "In8.Cu" signal "VCC")
		(20 "In9.Cu" signal "VCC1")
		(22 "In10.Cu" signal "GND4")
		(24 "In11.Cu" signal "IN4")
		(26 "In12.Cu" signal "GND5")
		(28 "In13.Cu" signal "IN5")
		(30 "In14.Cu" signal "GND6")
		(32 "In15.Cu" signal "IN6")
		(34 "In16.Cu" signal "GND7")
		(2 "B.Cu" signal "BOTTOM")
		(9 "F.Adhes" user "F.Adhesive")
		(11 "B.Adhes" user "B.Adhesive")
		(13 "F.Paste" user "Package Geometry/Pastemask Top")
		(15 "B.Paste" user "Package Geometry/Pastemask Bottom")
		(5 "F.SilkS" user "Ref Des/Silkscreen Top")
		(7 "B.SilkS" user "Ref Des/Silkscreen Bottom")
		(1 "F.Mask" user "Board Geometry/Soldermask Top")
		(3 "B.Mask" user "Board Geometry/Soldermask Bottom")
		(17 "Dwgs.User" user "User.Drawings")
		(19 "Cmts.User" user "User.Comments")
		(21 "Eco1.User" user "User.Eco1")
		(23 "Eco2.User" user "User.Eco2")
		(25 "Edge.Cuts" user "Board Geometry/Outline")
		(27 "Margin" user)
		(31 "F.CrtYd" user "Package Geometry/Place Bound Top")
		(29 "B.CrtYd" user "Package Geometry/Place Bound Bottom")
		(35 "F.Fab" user "Ref Des/Assembly Top")
		(33 "B.Fab" user "Ref Des/Assembly Bottom")
	)
	(footprint ""
		(layer "F.Cu")
		(at 359.867962 -258.880102 180)
		(property "Reference" "U25"
			(at -45.78477 -62.086744 0)
			(unlocked yes)
			(layer "F.SilkS")
			(effects
				(font
					(size 0.7874 0.5842)
					(thickness 0.1524)
				)
			)
		)
		(property "Value" ""
			(at 0 0 180)
			(layer "F.Fab")
			(effects
				(font
					(size 1.27 1.27)
				)
			)
		)
		(duplicate_pad_numbers_are_jumpers no)
		(pad "AR16" smd circle
			(at -20.059904 -9.269984 180)
			(size 0.450088 0.450088)
			(layers "F.Cu" "F.Mask" "F.Paste")
			(net "GND")
		)
		(pad "AR17" smd circle
			(at -19.120104 -9.269984 180)
			(size 0.450088 0.450088)
			(layers "F.Cu" "F.Mask" "F.Paste")
			(net "M_J_CPU0_SA_CB<7>")
		)
		(pad "AR18" smd circle
			(at -18.18005 -9.269984 180)
			(size 0.450088 0.450088)
			(layers "F.Cu" "F.Mask" "F.Paste")
			(net "PVDDCR_SOC_P0")
		)
		(pad "AR19" smd circle
			(at -17.239996 -9.269984 180)
			(size 0.450088 0.450088)
			(layers "F.Cu" "F.Mask" "F.Paste")
			(net "GND")
		)
		(pad "AR20" smd circle
			(at -16.299942 -9.269984 180)
			(size 0.450088 0.450088)
			(layers "F.Cu" "F.Mask" "F.Paste")
			(net "GND")
		)
		(pad "AR21" smd circle
			(at -15.359888 -9.269984 180)
			(size 0.450088 0.450088)
			(layers "F.Cu" "F.Mask" "F.Paste")
			(net "M_I_CPU0_SA_CB<7>")
		)
		(pad "AR22" smd circle
			(at -14.420088 -9.269984 180)
			(size 0.450088 0.450088)
			(layers "F.Cu" "F.Mask" "F.Paste")
			(net "GND")
		)
		(pad "AR23" smd circle
			(at -13.480034 -9.269984 180)
			(size 0.450088 0.450088)
			(layers "F.Cu" "F.Mask" "F.Paste")
			(net "PVDDCR_CPU0_P0")
		)
		(pad "AR24" smd circle
			(at -12.53998 -9.269984 180)
			(size 0.450088 0.450088)
			(layers "F.Cu" "F.Mask" "F.Paste")
			(net "GND")
		)
		(pad "AR25" smd circle
			(at -11.599926 -9.269984 180)
			(size 0.450088 0.450088)
			(layers "F.Cu" "F.Mask" "F.Paste")
			(net "PVDDCR_CPU0_P0")
		)
		(pad "AR26" smd circle
			(at -10.659872 -9.269984 180)
			(size 0.450088 0.450088)
			(layers "F.Cu" "F.Mask" "F.Paste")
			(net "GND")
		)
		(pad "AR27" smd circle
			(at -9.720072 -9.269984 180)
			(size 0.450088 0.450088)
			(layers "F.Cu" "F.Mask" "F.Paste")
			(net "PVDDCR_CPU0_P0")
		)
		(pad "AR28" smd circle
			(at -8.780018 -9.269984 180)
			(size 0.450088 0.450088)
			(layers "F.Cu" "F.Mask" "F.Paste")
			(net "GND")
		)
		(pad "AR29" smd circle
			(at -7.839964 -9.269984 180)
			(size 0.450088 0.450088)
			(layers "F.Cu" "F.Mask" "F.Paste")
			(net "PVDDCR_CPU0_P0")
		)
		(pad "AR30" smd circle
			(at -6.89991 -9.269984 180)
			(size 0.450088 0.450088)
			(layers "F.Cu" "F.Mask" "F.Paste")
			(net "GND")
		)
		(pad "AR31" smd circle
			(at -5.96011 -9.269984 180)
			(size 0.450088 0.450088)
			(layers "F.Cu" "F.Mask" "F.Paste")
			(net "PVDDCR_CPU0_P0")
		)
		(pad "AR32" smd circle
			(at -5.020056 -9.269984 180)
			(size 0.450088 0.450088)
			(layers "F.Cu" "F.Mask" "F.Paste")
			(net "GND")
		)
		(pad "AR33" smd circle
			(at -4.080002 -9.269984 180)
			(size 0.450088 0.450088)
			(layers "F.Cu" "F.Mask" "F.Paste")
			(net "PVDDCR_CPU0_P0")
		)
		(pad "AR34" smd circle
			(at -3.139948 -9.269984 180)
			(size 0.450088 0.450088)
			(layers "F.Cu" "F.Mask" "F.Paste")
			(net "GND")
		)
		(pad "AR35" smd circle
			(at -2.199894 -9.269984 180)
			(size 0.450088 0.450088)
			(layers "F.Cu" "F.Mask" "F.Paste")
			(net "PVDDCR_CPU0_P0")
		)
		(pad "AR36" smd circle
			(at -1.260094 -9.269984 180)
			(size 0.450088 0.450088)
			(layers "F.Cu" "F.Mask" "F.Paste")
			(net "GND")
		)
		(pad "AR40" smd circle
			(at 1.560068 -9.269984 180)
			(size 0.450088 0.450088)
			(layers "F.Cu" "F.Mask" "F.Paste")
			(net "PVDDCR_CPU0_P0")
		)
		(pad "AR41" smd circle
			(at 2.500122 -9.269984 180)
			(size 0.450088 0.450088)
			(layers "F.Cu" "F.Mask" "F.Paste")
			(net "GND")
		)
		(pad "AR42" smd circle
			(at 3.439922 -9.269984 180)
			(size 0.450088 0.450088)
			(layers "F.Cu" "F.Mask" "F.Paste")
			(net "PVDDCR_CPU0_P0")
		)
		(pad "AR43" smd circle
			(at 4.379976 -9.269984 180)
			(size 0.450088 0.450088)
			(layers "F.Cu" "F.Mask" "F.Paste")
			(net "GND")
		)
		(pad "AR44" smd circle
			(at 5.32003 -9.269984 180)
			(size 0.450088 0.450088)
			(layers "F.Cu" "F.Mask" "F.Paste")
			(net "PVDDCR_CPU0_P0")
		)
		(pad "AR45" smd circle
			(at 6.260084 -9.269984 180)
			(size 0.450088 0.450088)
			(layers "F.Cu" "F.Mask" "F.Paste")
			(net "GND")
		)
		(pad "AR46" smd circle
			(at 7.199884 -9.269984 180)
			(size 0.450088 0.450088)
			(layers "F.Cu" "F.Mask" "F.Paste")
			(net "PVDDCR_CPU0_P0")
		)
		(pad "AR47" smd circle
			(at 8.139938 -9.269984 180)
			(size 0.450088 0.450088)
			(layers "F.Cu" "F.Mask" "F.Paste")
			(net "GND")
		)
		(pad "AR48" smd circle
			(at 9.079992 -9.269984 180)
			(size 0.450088 0.450088)
			(layers "F.Cu" "F.Mask" "F.Paste")
			(net "PVDDCR_CPU0_P0")
		)
		(pad "AR49" smd circle
			(at 10.020046 -9.269984 180)
			(size 0.450088 0.450088)
			(layers "F.Cu" "F.Mask" "F.Paste")
			(net "GND")
		)
		(pad "AR50" smd circle
			(at 10.9601 -9.269984 180)
			(size 0.450088 0.450088)
			(layers "F.Cu" "F.Mask" "F.Paste")
			(net "PVDDCR_CPU0_P0")
		)
		(pad "AR51" smd circle
			(at 11.8999 -9.269984 180)
			(size 0.450088 0.450088)
			(layers "F.Cu" "F.Mask" "F.Paste")
			(net "GND")
		)
		(pad "AR52" smd circle
			(at 12.839954 -9.269984 180)
			(size 0.450088 0.450088)
			(layers "F.Cu" "F.Mask" "F.Paste")
			(net "PVDD18_S5_P0")
		)
		(pad "AR53" smd circle
			(at 13.780008 -9.269984 180)
			(size 0.450088 0.450088)
			(layers "F.Cu" "F.Mask" "F.Paste")
			(net "GND")
		)
		(pad "AR54" smd circle
			(at 14.720062 -9.269984 180)
			(size 0.450088 0.450088)
			(layers "F.Cu" "F.Mask" "F.Paste")
			(net "PVDD18_S5_P0")
		)
		(pad "AR55" smd circle
			(at 15.660116 -9.269984 180)
			(size 0.450088 0.450088)
			(layers "F.Cu" "F.Mask" "F.Paste")
			(net "M_C_CPU0_SA_CB<7>")
		)
		(pad "AR56" smd circle
			(at 16.599916 -9.269984 180)
			(size 0.450088 0.450088)
			(layers "F.Cu" "F.Mask" "F.Paste")
			(net "GND")
		)
		(pad "AR57" smd circle
			(at 17.53997 -9.269984 180)
			(size 0.450088 0.450088)
			(layers "F.Cu" "F.Mask" "F.Paste")
			(net "GND")
		)
		(pad "AR58" smd circle
			(at 18.480024 -9.269984 180)
			(size 0.450088 0.450088)
			(layers "F.Cu" "F.Mask" "F.Paste")
			(net "PVDDIO_P0")
		)
		(pad "AR59" smd circle
			(at 19.420078 -9.269984 180)
			(size 0.450088 0.450088)
			(layers "F.Cu" "F.Mask" "F.Paste")
			(net "M_D_CPU0_SA_CB<7>")
		)
		(pad "AR60" smd circle
			(at 20.359878 -9.269984 180)
			(size 0.450088 0.450088)
			(layers "F.Cu" "F.Mask" "F.Paste")
			(net "GND")
		)
		(pad "AR61" smd circle
			(at 21.299932 -9.269984 180)
			(size 0.450088 0.450088)
			(layers "F.Cu" "F.Mask" "F.Paste")
			(net "GND")
		)
		(pad "AR62" smd circle
			(at 22.239986 -9.269984 180)
			(size 0.450088 0.450088)
			(layers "F.Cu" "F.Mask" "F.Paste")
			(net "M_B_CPU0_SA_CB<7>")
		)
		(pad "AR63" smd circle
			(at 23.18004 -9.269984 180)
			(size 0.450088 0.450088)
			(layers "F.Cu" "F.Mask" "F.Paste")
			(net "GND")
		)
		(pad "AR64" smd circle
			(at 24.120094 -9.269984 180)
			(size 0.450088 0.450088)
			(layers "F.Cu" "F.Mask" "F.Paste")
			(net "GND")
		)
		(pad "AR65" smd circle
			(at 25.059894 -9.269984 180)
			(size 0.450088 0.450088)
			(layers "F.Cu" "F.Mask" "F.Paste")
			(net "PVDDIO_P0")
		)
		(pad "AR66" smd circle
			(at 25.999948 -9.269984 180)
			(size 0.450088 0.450088)
			(layers "F.Cu" "F.Mask" "F.Paste")
			(net "M_F_CPU0_SA_CB<7>")
		)
		(pad "AR67" smd circle
			(at 26.940002 -9.269984 180)
			(size 0.450088 0.450088)
			(layers "F.Cu" "F.Mask" "F.Paste")
			(net "GND")
		)
		(pad "AR68" smd circle
			(at 27.880056 -9.269984 180)
			(size 0.450088 0.450088)
			(layers "F.Cu" "F.Mask" "F.Paste")
			(net "GND")
		)
		(pad "AR69" smd circle
			(at 28.82011 -9.269984 180)
			(size 0.450088 0.450088)
			(layers "F.Cu" "F.Mask" "F.Paste")
			(net "M_E_CPU0_SA_CB<7>")
		)
		(pad "AR70" smd circle
			(at 29.75991 -9.269984 180)
			(size 0.450088 0.450088)
			(layers "F.Cu" "F.Mask" "F.Paste")
			(net "GND")
		)
		(pad "AR71" smd circle
			(at 30.699964 -9.269984 180)
			(size 0.450088 0.450088)
			(layers "F.Cu" "F.Mask" "F.Paste")
			(net "GND")
		)
		(pad "AR72" smd circle
			(at 31.640018 -9.269984 180)
			(size 0.450088 0.450088)
			(layers "F.Cu" "F.Mask" "F.Paste")
			(net "PVDDIO_P0")
		)
		(pad "AR73" smd circle
			(at 32.580072 -9.269984 180)
			(size 0.450088 0.450088)
			(layers "F.Cu" "F.Mask" "F.Paste")
			(net "M_A_CPU0_SA_CB<7>")
		)
		(pad "AR74" smd circle
			(at 33.519872 -9.269984 180)
			(size 0.450088 0.450088)
			(layers "F.Cu" "F.Mask" "F.Paste")
			(net "M_A_CPU0_ALERT_R_N")
		)
		(pad "AR75" smd circle
			(at 34.459926 -9.269984 180)
			(size 0.450088 0.450088)
			(layers "F.Cu" "F.Mask" "F.Paste")
			(net "GND")
		)
		(pad "AT2" smd circle
			(at -33.690052 -8.459978 180)
			(size 0.450088 0.450088)
			(layers "F.Cu" "F.Mask" "F.Paste")
			(net "M_G_CPU0_RESET_N")
		)
		(pad "AT3" smd circle
			(at -32.749998 -8.459978 180)
			(size 0.450088 0.450088)
			(layers "F.Cu" "F.Mask" "F.Paste")
			(net "GND")
		)
		(pad "AT4" smd circle
			(at -31.809944 -8.459978 180)
			(size 0.450088 0.450088)
			(layers "F.Cu" "F.Mask" "F.Paste")
			(net "GND")
		)
		(pad "AT5" smd circle
			(at -30.86989 -8.459978 180)
			(size 0.450088 0.450088)
			(layers "F.Cu" "F.Mask" "F.Paste")
			(net "GND")
		)
		(pad "AT6" smd circle
			(at -29.93009 -8.459978 180)
			(size 0.450088 0.450088)
			(layers "F.Cu" "F.Mask" "F.Paste")
			(net "GND")
		)
		(pad "AT7" smd circle
			(at -28.990036 -8.459978 180)
			(size 0.450088 0.450088)
			(layers "F.Cu" "F.Mask" "F.Paste")
			(net "M_K_CPU0_ALERT_R_N")
		)
		(pad "AT8" smd circle
			(at -28.049982 -8.459978 180)
			(size 0.450088 0.450088)
			(layers "F.Cu" "F.Mask" "F.Paste")
			(net "GND")
		)
		(pad "AT9" smd circle
			(at -27.109928 -8.459978 180)
			(size 0.450088 0.450088)
			(layers "F.Cu" "F.Mask" "F.Paste")
			(net "GND")
		)
		(pad "AT10" smd circle
			(at -26.170128 -8.459978 180)
			(size 0.450088 0.450088)
			(layers "F.Cu" "F.Mask" "F.Paste")
			(net "GND")
		)
		(pad "AT11" smd circle
			(at -25.230074 -8.459978 180)
			(size 0.450088 0.450088)
			(layers "F.Cu" "F.Mask" "F.Paste")
			(net "M_L_CPU0_ALERT_R_N")
		)
		(pad "AT12" smd circle
			(at -24.29002 -8.459978 180)
			(size 0.450088 0.450088)
			(layers "F.Cu" "F.Mask" "F.Paste")
			(net "GND")
		)
		(pad "AT13" smd circle
			(at -23.349966 -8.459978 180)
			(size 0.450088 0.450088)
			(layers "F.Cu" "F.Mask" "F.Paste")
			(net "GND")
		)
		(pad "AT14" smd circle
			(at -22.409912 -8.459978 180)
			(size 0.450088 0.450088)
			(layers "F.Cu" "F.Mask" "F.Paste")
			(net "M_H_CPU0_ALERT_R_N")
		)
		(pad "AT15" smd circle
			(at -21.470112 -8.459978 180)
			(size 0.450088 0.450088)
			(layers "F.Cu" "F.Mask" "F.Paste")
			(net "GND")
		)
		(pad "AT16" smd circle
			(at -20.530058 -8.459978 180)
			(size 0.450088 0.450088)
			(layers "F.Cu" "F.Mask" "F.Paste")
			(net "GND")
		)
		(pad "AT17" smd circle
			(at -19.590004 -8.459978 180)
			(size 0.450088 0.450088)
			(layers "F.Cu" "F.Mask" "F.Paste")
			(net "GND")
		)
		(pad "AT18" smd circle
			(at -18.64995 -8.459978 180)
			(size 0.450088 0.450088)
			(layers "F.Cu" "F.Mask" "F.Paste")
			(net "M_J_CPU0_ALERT_R_N")
		)
		(pad "AT19" smd circle
			(at -17.709896 -8.459978 180)
			(size 0.450088 0.450088)
			(layers "F.Cu" "F.Mask" "F.Paste")
			(net "GND")
		)
		(pad "AT20" smd circle
			(at -16.770096 -8.459978 180)
			(size 0.450088 0.450088)
			(layers "F.Cu" "F.Mask" "F.Paste")
			(net "GND")
		)
		(pad "AT21" smd circle
			(at -15.830042 -8.459978 180)
			(size 0.450088 0.450088)
			(layers "F.Cu" "F.Mask" "F.Paste")
			(net "M_I_CPU0_ALERT_R_N")
		)
		(pad "AT22" smd circle
			(at -14.889988 -8.459978 180)
			(size 0.450088 0.450088)
			(layers "F.Cu" "F.Mask" "F.Paste")
			(net "PVDDCR_SOC_P0")
		)
		(pad "AT23" smd circle
			(at -13.949934 -8.459978 180)
			(size 0.450088 0.450088)
			(layers "F.Cu" "F.Mask" "F.Paste")
			(net "GND")
		)
		(pad "AT24" smd circle
			(at -13.00988 -8.459978 180)
			(size 0.450088 0.450088)
			(layers "F.Cu" "F.Mask" "F.Paste")
			(net "PVDDCR_CPU0_P0")
		)
		(pad "AT25" smd circle
			(at -12.07008 -8.459978 180)
			(size 0.450088 0.450088)
			(layers "F.Cu" "F.Mask" "F.Paste")
			(net "GND")
		)
		(pad "AT26" smd circle
			(at -11.130026 -8.459978 180)
			(size 0.450088 0.450088)
			(layers "F.Cu" "F.Mask" "F.Paste")
			(net "PVDDCR_CPU0_P0")
		)
		(pad "AT27" smd circle
			(at -10.189972 -8.459978 180)
			(size 0.450088 0.450088)
			(layers "F.Cu" "F.Mask" "F.Paste")
			(net "GND")
		)
		(pad "AT28" smd circle
			(at -9.249918 -8.459978 180)
			(size 0.450088 0.450088)
			(layers "F.Cu" "F.Mask" "F.Paste")
			(net "PVDDCR_CPU0_P0")
		)
		(pad "AT29" smd circle
			(at -8.310118 -8.459978 180)
			(size 0.450088 0.450088)
			(layers "F.Cu" "F.Mask" "F.Paste")
			(net "GND")
		)
		(pad "AT30" smd circle
			(at -7.370064 -8.459978 180)
			(size 0.450088 0.450088)
			(layers "F.Cu" "F.Mask" "F.Paste")
			(net "PVDDCR_CPU0_P0")
		)
		(pad "AT31" smd circle
			(at -6.43001 -8.459978 180)
			(size 0.450088 0.450088)
			(layers "F.Cu" "F.Mask" "F.Paste")
			(net "GND")
		)
		(pad "AT32" smd circle
			(at -5.489956 -8.459978 180)
			(size 0.450088 0.450088)
			(layers "F.Cu" "F.Mask" "F.Paste")
			(net "PVDDCR_CPU0_P0")
		)
		(pad "AT33" smd circle
			(at -4.549902 -8.459978 180)
			(size 0.450088 0.450088)
			(layers "F.Cu" "F.Mask" "F.Paste")
			(net "GND")
		)
		(pad "AT34" smd circle
			(at -3.610102 -8.459978 180)
			(size 0.450088 0.450088)
			(layers "F.Cu" "F.Mask" "F.Paste")
			(net "PVDDCR_CPU0_P0")
		)
		(pad "AT35" smd circle
			(at -2.670048 -8.459978 180)
			(size 0.450088 0.450088)
			(layers "F.Cu" "F.Mask" "F.Paste")
			(net "GND")
		)
		(pad "AT36" smd circle
			(at -1.729994 -8.459978 180)
			(size 0.450088 0.450088)
			(layers "F.Cu" "F.Mask" "F.Paste")
			(net "PVDDCR_CPU0_P0")
		)
		(pad "AT37" smd circle
			(at -0.78994 -8.459978 180)
			(size 0.450088 0.450088)
			(layers "F.Cu" "F.Mask" "F.Paste")
			(net "GND")
		)
		(pad "AT39" smd circle
			(at 1.089914 -8.459978 180)
			(size 0.450088 0.450088)
			(layers "F.Cu" "F.Mask" "F.Paste")
			(net "PVDDCR_CPU0_P0")
		)
		(pad "AT40" smd circle
			(at 2.029968 -8.459978 180)
			(size 0.450088 0.450088)
			(layers "F.Cu" "F.Mask" "F.Paste")
			(net "GND")
		)
		(pad "AT41" smd circle
			(at 2.970022 -8.459978 180)
			(size 0.450088 0.450088)
			(layers "F.Cu" "F.Mask" "F.Paste")
			(net "PVDDCR_CPU0_P0")
		)
		(pad "AT42" smd circle
			(at 3.910076 -8.459978 180)
			(size 0.450088 0.450088)
			(layers "F.Cu" "F.Mask" "F.Paste")
			(net "GND")
		)
		(pad "AT43" smd circle
			(at 4.849876 -8.459978 180)
			(size 0.450088 0.450088)
			(layers "F.Cu" "F.Mask" "F.Paste")
			(net "PVDDCR_CPU0_P0")
		)
		(pad "AT44" smd circle
			(at 5.78993 -8.459978 180)
			(size 0.450088 0.450088)
			(layers "F.Cu" "F.Mask" "F.Paste")
			(net "GND")
		)
		(pad "AT45" smd circle
			(at 6.729984 -8.459978 180)
			(size 0.450088 0.450088)
			(layers "F.Cu" "F.Mask" "F.Paste")
			(net "PVDDCR_CPU0_P0")
		)
		(pad "AT46" smd circle
			(at 7.670038 -8.459978 180)
			(size 0.450088 0.450088)
			(layers "F.Cu" "F.Mask" "F.Paste")
			(net "GND")
		)
		(pad "AT47" smd circle
			(at 8.610092 -8.459978 180)
			(size 0.450088 0.450088)
			(layers "F.Cu" "F.Mask" "F.Paste")
			(net "PVDDCR_CPU0_P0")
		)
		(pad "AT48" smd circle
			(at 9.549892 -8.459978 180)
			(size 0.450088 0.450088)
			(layers "F.Cu" "F.Mask" "F.Paste")
			(net "GND")
		)
		(pad "AT49" smd circle
			(at 10.489946 -8.459978 180)
			(size 0.450088 0.450088)
			(layers "F.Cu" "F.Mask" "F.Paste")
			(net "PVDDCR_CPU0_P0")
		)
		(pad "AT50" smd circle
			(at 11.43 -8.459978 180)
			(size 0.450088 0.450088)
			(layers "F.Cu" "F.Mask" "F.Paste")
			(net "GND")
		)
		(pad "AT51" smd circle
			(at 12.370054 -8.459978 180)
			(size 0.450088 0.450088)
			(layers "F.Cu" "F.Mask" "F.Paste")
			(net "PVDD18_S5_P0")
		)
		(pad "AT52" smd circle
			(at 13.310108 -8.459978 180)
			(size 0.450088 0.450088)
			(layers "F.Cu" "F.Mask" "F.Paste")
			(net "GND")
		)
		(pad "AT53" smd circle
			(at 14.249908 -8.459978 180)
			(size 0.450088 0.450088)
			(layers "F.Cu" "F.Mask" "F.Paste")
			(net "PVDD18_S5_P0")
		)
		(pad "AT54" smd circle
			(at 15.189962 -8.459978 180)
			(size 0.450088 0.450088)
			(layers "F.Cu" "F.Mask" "F.Paste")
			(net "GND")
		)
		(pad "AT55" smd circle
			(at 16.130016 -8.459978 180)
			(size 0.450088 0.450088)
			(layers "F.Cu" "F.Mask" "F.Paste")
			(net "M_C_CPU0_ALERT_R_N")
		)
		(pad "AT56" smd circle
			(at 17.07007 -8.459978 180)
			(size 0.450088 0.450088)
			(layers "F.Cu" "F.Mask" "F.Paste")
			(net "GND")
		)
		(pad "AT57" smd circle
			(at 18.010124 -8.459978 180)
			(size 0.450088 0.450088)
			(layers "F.Cu" "F.Mask" "F.Paste")
			(net "GND")
		)
		(pad "AT58" smd circle
			(at 18.949924 -8.459978 180)
			(size 0.450088 0.450088)
			(layers "F.Cu" "F.Mask" "F.Paste")
			(net "M_D_CPU0_ALERT_R_N")
		)
		(pad "AT59" smd circle
			(at 19.889978 -8.459978 180)
			(size 0.450088 0.450088)
			(layers "F.Cu" "F.Mask" "F.Paste")
			(net "GND")
		)
	)
)
